(kicad_pcb
	(version 20260206)
	(generator "pcbnew")
	(generator_version "10.0")
	(general
		(thickness 1.6)
		(legacy_teardrops no)
	)
	(paper "A4")
	(title_block
		(title "15969-1a.1015WZS0858.brd")
		(comment 1 "Tioga Pass / footprints 276-282 of 295")
	)
	(layers
		(0 "F.Cu" signal "TOP")
		(4 "In1.Cu" signal "L2GND")
		(6 "In2.Cu" signal "L3")
		(8 "In3.Cu" signal "L4")
		(10 "In4.Cu" signal "L5GND")
		(2 "B.Cu" signal "BOTTOM")
		(9 "F.Adhes" user "F.Adhesive")
		(11 "B.Adhes" user "B.Adhesive")
		(13 "F.Paste" user "Package Geometry/Pastemask Top")
		(15 "B.Paste" user "Package Geometry/Pastemask Bottom")
		(5 "F.SilkS" user "Ref Des/Silkscreen Top")
		(7 "B.SilkS" user "Ref Des/Silkscreen Bottom")
		(1 "F.Mask" user "Board Geometry/Soldermask Top")
		(3 "B.Mask" user "Board Geometry/Soldermask Bottom")
		(17 "Dwgs.User" user "User.Drawings")
		(19 "Cmts.User" user "User.Comments")
		(21 "Eco1.User" user "User.Eco1")
		(23 "Eco2.User" user "User.Eco2")
		(25 "Edge.Cuts" user "Board Geometry/Outline")
		(27 "Margin" user)
		(31 "F.CrtYd" user "Package Geometry/Place Bound Top")
		(29 "B.CrtYd" user "Package Geometry/Place Bound Bottom")
		(35 "F.Fab" user "Ref Des/Assembly Top")
		(33 "B.Fab" user "Ref Des/Assembly Bottom")
	)
	(footprint ""
		(layer "B.Cu")
		(at 119.9388 -14.6304 -90)
		(property "Reference" "RU96"
			(at 0 0 90)
			(layer "B.SilkS")
			(hide yes)
			(effects
				(font
					(size 1.27 1.27)
				)
				(justify mirror)
			)
		)
		(property "Value" "10KR2F-2-GP"
			(at -0.064008 -3.993896 270)
			(unlocked yes)
			(layer "B.Fab")
			(hide yes)
			(effects
				(font
					(size 1.016 1.016)
					(thickness 0.1524)
				)
				(justify mirror)
			)
		)
		(property "Device Type" "R402H16"
			(at -0.064008 -5.517896 270)
			(unlocked yes)
			(layer "B.Fab")
			(hide yes)
			(effects
				(font
					(size 1.016 1.016)
					(thickness 0.1524)
				)
				(justify mirror)
			)
		)
		(duplicate_pad_numbers_are_jumpers no)
		(fp_line
			(start -0.508 -0.9398)
			(end 0.508 -0.9398)
			(stroke
				(width 0.1524)
				(type default)
			)
			(layer "B.SilkS")
		)
		(fp_line
			(start 0.508 -0.9398)
			(end 0.508 0.9398)
			(stroke
				(width 0.1524)
				(type default)
			)
			(layer "B.SilkS")
		)
		(fp_rect
			(start 0.508 0.9398)
			(end -0.508 -0.9398)
			(stroke
				(width 0)
				(type default)
			)
			(fill no)
			(layer "B.CrtYd")
		)
		(fp_rect
			(start 0.508 0.9398)
			(end -0.508 -0.9398)
			(stroke
				(width 0)
				(type default)
			)
			(fill no)
			(layer "B.Fab")
		)
		(pad "1" smd custom
			(at 0 -0.4445 90)
			(size 0.1397 0.1397)
			(layers "B.Cu" "B.Mask" "B.Paste")
			(net "SMB_U_REPEATER_EN")
			(options
				(clearance outline)
				(anchor circle)
			)
			(primitives
				(gr_poly
					(pts
						(arc
							(start -0.1778 0.2794)
							(mid -0.249642 0.249642)
							(end -0.2794 0.1778)
						)
						(arc
							(start -0.2794 -0.1778)
							(mid -0.249642 -0.249642)
							(end -0.1778 -0.2794)
						)
						(arc
							(start 0.1778 -0.2794)
							(mid 0.249642 -0.249642)
							(end 0.2794 -0.1778)
						)
						(arc
							(start 0.2794 0.1778)
							(mid 0.249642 0.249642)
							(end 0.1778 0.2794)
						)
					)
					(width 0)
					(fill yes)
				)
			)
		)
		(pad "2" smd custom
			(at 0 0.4445 90)
			(size 0.1397 0.1397)
			(layers "B.Cu" "B.Mask" "B.Paste")
			(net "P3V3_USB_HUB")
			(options
				(clearance outline)
				(anchor circle)
			)
			(primitives
				(gr_poly
					(pts
						(arc
							(start -0.1778 0.2794)
							(mid -0.249642 0.249642)
							(end -0.2794 0.1778)
						)
						(arc
							(start -0.2794 -0.1778)
							(mid -0.249642 -0.249642)
							(end -0.1778 -0.2794)
						)
						(arc
							(start 0.1778 -0.2794)
							(mid 0.249642 -0.249642)
							(end 0.2794 -0.1778)
						)
						(arc
							(start 0.2794 0.1778)
							(mid 0.249642 0.249642)
							(end 0.1778 0.2794)
						)
					)
					(width 0)
					(fill yes)
				)
			)
		)
	)
	(footprint ""
		(layer "B.Cu")
		(at 14.5415 -25.9207 -135)
		(property "Reference" "C51"
			(at 0 0 45)
			(layer "B.SilkS")
			(hide yes)
			(effects
				(font
					(size 1.27 1.27)
				)
				(justify mirror)
			)
		)
		(property "Value" "SCD1U25V2KX-2-GP"
			(at -1.181083 -2.705137 225)
			(unlocked yes)
			(layer "B.Fab")
			(hide yes)
			(effects
				(font
					(size 1.016 1.016)
					(thickness 0.1524)
				)
				(justify mirror)
			)
		)
		(property "Device Type" "C402H22"
			(at -1.181263 -4.229087 225)
			(unlocked yes)
			(layer "B.Fab")
			(hide yes)
			(effects
				(font
					(size 1.016 1.016)
					(thickness 0.1524)
				)
				(justify mirror)
			)
		)
		(duplicate_pad_numbers_are_jumpers no)
		(fp_poly
			(pts
				(xy -0.431829 0.952626) (xy -0.431829 -0.952375) (xy 0.431771 -0.952374) (xy 0.431771 0.952626)
			)
			(stroke
				(width 0)
				(type default)
			)
			(fill no)
			(layer "B.CrtYd")
		)
		(fp_poly
			(pts
				(xy -0.431829 0.952626) (xy -0.431829 -0.952375) (xy 0.431771 -0.952374) (xy 0.431771 0.952626)
			)
			(stroke
				(width 0)
				(type default)
			)
			(fill no)
			(layer "B.Fab")
		)
		(pad "1" smd custom
			(at 0 -0.4445 45)
			(size 0.1524 0.1524)
			(layers "B.Cu" "B.Mask" "B.Paste")
			(net "ATX_P12V_SENSE_VP_R")
			(options
				(clearance outline)
				(anchor circle)
			)
			(primitives
				(gr_poly
					(pts
						(arc
							(start 0.3048 0.2032)
							(mid 0.275042 0.275042)
							(end 0.2032 0.3048)
						)
						(arc
							(start -0.2032 0.3048)
							(mid -0.275042 0.275042)
							(end -0.3048 0.2032)
						)
						(arc
							(start -0.3048 -0.2032)
							(mid -0.275042 -0.275042)
							(end -0.2032 -0.3048)
						)
						(arc
							(start 0.2032 -0.3048)
							(mid 0.275042 -0.275042)
							(end 0.3048 -0.2032)
						)
					)
					(width 0)
					(fill yes)
				)
			)
		)
		(pad "2" smd custom
			(at 0 0.4445 45)
			(size 0.1524 0.1524)
			(layers "B.Cu" "B.Mask" "B.Paste")
			(net "ATX_P12V_SENSE_VN_R")
			(options
				(clearance outline)
				(anchor circle)
			)
			(primitives
				(gr_poly
					(pts
						(arc
							(start 0.3048 0.2032)
							(mid 0.275042 0.275042)
							(end 0.2032 0.3048)
						)
						(arc
							(start -0.2032 0.3048)
							(mid -0.275042 0.275042)
							(end -0.3048 0.2032)
						)
						(arc
							(start -0.3048 -0.2032)
							(mid -0.275042 -0.275042)
							(end -0.2032 -0.3048)
						)
						(arc
							(start 0.2032 -0.3048)
							(mid 0.275042 -0.275042)
							(end 0.3048 -0.2032)
						)
					)
					(width 0)
					(fill yes)
				)
			)
		)
	)
	(footprint ""
		(layer "B.Cu")
		(at 32.7787 -1.6129)
		(property "Reference" "R60"
			(at 0 0 0)
			(layer "B.SilkS")
			(hide yes)
			(effects
				(font
					(size 1.27 1.27)
				)
				(justify mirror)
			)
		)
		(property "Value" "0R2F-1-GP"
			(at -0.064008 -3.993896 0)
			(unlocked yes)
			(layer "B.Fab")
			(hide yes)
			(effects
				(font
					(size 1.016 1.016)
					(thickness 0.1524)
				)
				(justify mirror)
			)
		)
		(property "Device Type" "R402H16"
			(at -0.064008 -5.517896 0)
			(unlocked yes)
			(layer "B.Fab")
			(hide yes)
			(effects
				(font
					(size 1.016 1.016)
					(thickness 0.1524)
				)
				(justify mirror)
			)
		)
		(duplicate_pad_numbers_are_jumpers no)
		(fp_line
			(start -0.508 -0.9398)
			(end 0.508 -0.9398)
			(stroke
				(width 0.1524)
				(type default)
			)
			(layer "B.SilkS")
		)
		(fp_line
			(start 0.508 -0.9398)
			(end 0.508 0.9398)
			(stroke
				(width 0.1524)
				(type default)
			)
			(layer "B.SilkS")
		)
		(fp_rect
			(start 0.508 0.9398)
			(end -0.508 -0.9398)
			(stroke
				(width 0)
				(type default)
			)
			(fill no)
			(layer "B.CrtYd")
		)
		(fp_rect
			(start 0.508 0.9398)
			(end -0.508 -0.9398)
			(stroke
				(width 0)
				(type default)
			)
			(fill no)
			(layer "B.Fab")
		)
		(pad "1" smd custom
			(at 0 -0.4445 180)
			(size 0.1397 0.1397)
			(layers "B.Cu" "B.Mask" "B.Paste")
			(net "PD_SLOT2_PRSNT1")
			(options
				(clearance outline)
				(anchor circle)
			)
			(primitives
				(gr_poly
					(pts
						(arc
							(start -0.1778 0.2794)
							(mid -0.249642 0.249642)
							(end -0.2794 0.1778)
						)
						(arc
							(start -0.2794 -0.1778)
							(mid -0.249642 -0.249642)
							(end -0.1778 -0.2794)
						)
						(arc
							(start 0.1778 -0.2794)
							(mid 0.249642 -0.249642)
							(end 0.2794 -0.1778)
						)
						(arc
							(start 0.2794 0.1778)
							(mid 0.249642 0.249642)
							(end 0.1778 0.2794)
						)
					)
					(width 0)
					(fill yes)
				)
			)
		)
		(pad "2" smd custom
			(at 0 0.4445 180)
			(size 0.1397 0.1397)
			(layers "B.Cu" "B.Mask" "B.Paste")
			(net "GND")
			(options
				(clearance outline)
				(anchor circle)
			)
			(primitives
				(gr_poly
					(pts
						(arc
							(start -0.1778 0.2794)
							(mid -0.249642 0.249642)
							(end -0.2794 0.1778)
						)
						(arc
							(start -0.2794 -0.1778)
							(mid -0.249642 -0.249642)
							(end -0.1778 -0.2794)
						)
						(arc
							(start 0.1778 -0.2794)
							(mid 0.249642 -0.249642)
							(end 0.2794 -0.1778)
						)
						(arc
							(start 0.2794 0.1778)
							(mid 0.249642 0.249642)
							(end 0.1778 0.2794)
						)
					)
					(width 0)
					(fill yes)
				)
			)
		)
	)
	(footprint ""
		(layer "B.Cu")
		(at 127.0762 -18.4404 90)
		(property "Reference" "CU60"
			(at 0 0 90)
			(layer "B.SilkS")
			(hide yes)
			(effects
				(font
					(size 1.27 1.27)
				)
				(justify mirror)
			)
		)
		(property "Value" "SCD1U16V2KX-3GP"
			(at -1.1811 -2.7051 90)
			(unlocked yes)
			(layer "B.Fab")
			(hide yes)
			(effects
				(font
					(size 1.016 1.016)
					(thickness 0.1524)
				)
				(justify mirror)
			)
		)
		(property "Device Type" "C402H22"
			(at -1.1811 -4.2291 90)
			(unlocked yes)
			(layer "B.Fab")
			(hide yes)
			(effects
				(font
					(size 1.016 1.016)
					(thickness 0.1524)
				)
				(justify mirror)
			)
		)
		(duplicate_pad_numbers_are_jumpers no)
		(fp_rect
			(start 0.4318 0.9525)
			(end -0.4318 -0.9525)
			(stroke
				(width 0)
				(type default)
			)
			(fill no)
			(layer "B.CrtYd")
		)
		(fp_rect
			(start 0.4318 0.9525)
			(end -0.4318 -0.9525)
			(stroke
				(width 0)
				(type default)
			)
			(fill no)
			(layer "B.Fab")
		)
		(pad "1" smd custom
			(at 0 -0.4445 270)
			(size 0.1524 0.1524)
			(layers "B.Cu" "B.Mask" "B.Paste")
			(net "P3V3_STBY")
			(options
				(clearance outline)
				(anchor circle)
			)
			(primitives
				(gr_poly
					(pts
						(arc
							(start 0.3048 0.2032)
							(mid 0.275042 0.275042)
							(end 0.2032 0.3048)
						)
						(arc
							(start -0.2032 0.3048)
							(mid -0.275042 0.275042)
							(end -0.3048 0.2032)
						)
						(arc
							(start -0.3048 -0.2032)
							(mid -0.275042 -0.275042)
							(end -0.2032 -0.3048)
						)
						(arc
							(start 0.2032 -0.3048)
							(mid 0.275042 -0.275042)
							(end 0.3048 -0.2032)
						)
					)
					(width 0)
					(fill yes)
				)
			)
		)
		(pad "2" smd custom
			(at 0 0.4445 270)
			(size 0.1524 0.1524)
			(layers "B.Cu" "B.Mask" "B.Paste")
			(net "GND")
			(options
				(clearance outline)
				(anchor circle)
			)
			(primitives
				(gr_poly
					(pts
						(arc
							(start 0.3048 0.2032)
							(mid 0.275042 0.275042)
							(end 0.2032 0.3048)
						)
						(arc
							(start -0.2032 0.3048)
							(mid -0.275042 0.275042)
							(end -0.3048 0.2032)
						)
						(arc
							(start -0.3048 -0.2032)
							(mid -0.275042 -0.275042)
							(end -0.2032 -0.3048)
						)
						(arc
							(start 0.2032 -0.3048)
							(mid 0.275042 -0.275042)
							(end 0.3048 -0.2032)
						)
					)
					(width 0)
					(fill yes)
				)
			)
		)
	)
	(footprint ""
		(layer "B.Cu")
		(at 127.3556 -27.4066 -90)
		(property "Reference" "CU6"
			(at 0 0 90)
			(layer "B.SilkS")
			(hide yes)
			(effects
				(font
					(size 1.27 1.27)
				)
				(justify mirror)
			)
		)
		(property "Value" "SC1U10V2KX-4-GP"
			(at -1.1811 -2.7051 270)
			(unlocked yes)
			(layer "B.Fab")
			(hide yes)
			(effects
				(font
					(size 1.016 1.016)
					(thickness 0.1524)
				)
				(justify mirror)
			)
		)
		(property "Device Type" "C402H22"
			(at -1.1811 -4.2291 270)
			(unlocked yes)
			(layer "B.Fab")
			(hide yes)
			(effects
				(font
					(size 1.016 1.016)
					(thickness 0.1524)
				)
				(justify mirror)
			)
		)
		(duplicate_pad_numbers_are_jumpers no)
		(fp_rect
			(start 0.4318 0.9525)
			(end -0.4318 -0.9525)
			(stroke
				(width 0)
				(type default)
			)
			(fill no)
			(layer "B.CrtYd")
		)
		(fp_rect
			(start 0.4318 0.9525)
			(end -0.4318 -0.9525)
			(stroke
				(width 0)
				(type default)
			)
			(fill no)
			(layer "B.Fab")
		)
		(pad "1" smd custom
			(at 0 -0.4445 90)
			(size 0.1524 0.1524)
			(layers "B.Cu" "B.Mask" "B.Paste")
			(net "P3V3_USB_HUB")
			(options
				(clearance outline)
				(anchor circle)
			)
			(primitives
				(gr_poly
					(pts
						(arc
							(start 0.3048 0.2032)
							(mid 0.275042 0.275042)
							(end 0.2032 0.3048)
						)
						(arc
							(start -0.2032 0.3048)
							(mid -0.275042 0.275042)
							(end -0.3048 0.2032)
						)
						(arc
							(start -0.3048 -0.2032)
							(mid -0.275042 -0.275042)
							(end -0.2032 -0.3048)
						)
						(arc
							(start 0.2032 -0.3048)
							(mid 0.275042 -0.275042)
							(end 0.3048 -0.2032)
						)
					)
					(width 0)
					(fill yes)
				)
			)
		)
		(pad "2" smd custom
			(at 0 0.4445 90)
			(size 0.1524 0.1524)
			(layers "B.Cu" "B.Mask" "B.Paste")
			(net "GND")
			(options
				(clearance outline)
				(anchor circle)
			)
			(primitives
				(gr_poly
					(pts
						(arc
							(start 0.3048 0.2032)
							(mid 0.275042 0.275042)
							(end 0.2032 0.3048)
						)
						(arc
							(start -0.2032 0.3048)
							(mid -0.275042 0.275042)
							(end -0.3048 0.2032)
						)
						(arc
							(start -0.3048 -0.2032)
							(mid -0.275042 -0.275042)
							(end -0.2032 -0.3048)
						)
						(arc
							(start 0.2032 -0.3048)
							(mid 0.275042 -0.275042)
							(end 0.3048 -0.2032)
						)
					)
					(width 0)
					(fill yes)
				)
			)
		)
	)
	(footprint ""
		(layer "B.Cu")
		(at 15.6972 -10.0076)
		(property "Reference" "PC11"
			(at 0 0 0)
			(layer "B.SilkS")
			(hide yes)
			(effects
				(font
					(size 1.27 1.27)
				)
				(justify mirror)
			)
		)
		(property "Value" "SCD022U16V2KX-3DLGP"
			(at -1.1811 -2.7051 0)
			(unlocked yes)
			(layer "B.Fab")
			(hide yes)
			(effects
				(font
					(size 1.016 1.016)
					(thickness 0.1524)
				)
				(justify mirror)
			)
		)
		(property "Device Type" "C402H22"
			(at -1.1811 -4.2291 0)
			(unlocked yes)
			(layer "B.Fab")
			(hide yes)
			(effects
				(font
					(size 1.016 1.016)
					(thickness 0.1524)
				)
				(justify mirror)
			)
		)
		(duplicate_pad_numbers_are_jumpers no)
		(fp_rect
			(start 0.4318 0.9525)
			(end -0.4318 -0.9525)
			(stroke
				(width 0)
				(type default)
			)
			(fill no)
			(layer "B.CrtYd")
		)
		(fp_rect
			(start 0.4318 0.9525)
			(end -0.4318 -0.9525)
			(stroke
				(width 0)
				(type default)
			)
			(fill no)
			(layer "B.Fab")
		)
		(pad "1" smd custom
			(at 0 -0.4445 180)
			(size 0.1524 0.1524)
			(layers "B.Cu" "B.Mask" "B.Paste")
			(net "P3V3_TRK")
			(options
				(clearance outline)
				(anchor circle)
			)
			(primitives
				(gr_poly
					(pts
						(arc
							(start 0.3048 0.2032)
							(mid 0.275042 0.275042)
							(end 0.2032 0.3048)
						)
						(arc
							(start -0.2032 0.3048)
							(mid -0.275042 0.275042)
							(end -0.3048 0.2032)
						)
						(arc
							(start -0.3048 -0.2032)
							(mid -0.275042 -0.275042)
							(end -0.2032 -0.3048)
						)
						(arc
							(start 0.2032 -0.3048)
							(mid 0.275042 -0.275042)
							(end 0.3048 -0.2032)
						)
					)
					(width 0)
					(fill yes)
				)
			)
		)
		(pad "2" smd custom
			(at 0 0.4445 180)
			(size 0.1524 0.1524)
			(layers "B.Cu" "B.Mask" "B.Paste")
			(net "AGND_P3V3")
			(options
				(clearance outline)
				(anchor circle)
			)
			(primitives
				(gr_poly
					(pts
						(arc
							(start 0.3048 0.2032)
							(mid 0.275042 0.275042)
							(end 0.2032 0.3048)
						)
						(arc
							(start -0.2032 0.3048)
							(mid -0.275042 0.275042)
							(end -0.3048 0.2032)
						)
						(arc
							(start -0.3048 -0.2032)
							(mid -0.275042 -0.275042)
							(end -0.2032 -0.3048)
						)
						(arc
							(start 0.2032 -0.3048)
							(mid 0.275042 -0.275042)
							(end 0.3048 -0.2032)
						)
					)
					(width 0)
					(fill yes)
				)
			)
		)
	)
	(footprint ""
		(layer "B.Cu")
		(at 127.2794 -29.1084 -90)
		(property "Reference" "CU8"
			(at 0 0 90)
			(layer "B.SilkS")
			(hide yes)
			(effects
				(font
					(size 1.27 1.27)
				)
				(justify mirror)
			)
		)
		(property "Value" "SC1U10V2KX-4-GP"
			(at -1.1811 -2.7051 270)
			(unlocked yes)
			(layer "B.Fab")
			(hide yes)
			(effects
				(font
					(size 1.016 1.016)
					(thickness 0.1524)
				)
				(justify mirror)
			)
		)
		(property "Device Type" "C402H22"
			(at -1.1811 -4.2291 270)
			(unlocked yes)
			(layer "B.Fab")
			(hide yes)
			(effects
				(font
					(size 1.016 1.016)
					(thickness 0.1524)
				)
				(justify mirror)
			)
		)
		(duplicate_pad_numbers_are_jumpers no)
		(fp_rect
			(start 0.4318 0.9525)
			(end -0.4318 -0.9525)
			(stroke
				(width 0)
				(type default)
			)
			(fill no)
			(layer "B.CrtYd")
		)
		(fp_rect
			(start 0.4318 0.9525)
			(end -0.4318 -0.9525)
			(stroke
				(width 0)
				(type default)
			)
			(fill no)
			(layer "B.Fab")
		)
		(pad "1" smd custom
			(at 0 -0.4445 90)
			(size 0.1524 0.1524)
			(layers "B.Cu" "B.Mask" "B.Paste")
			(net "P3V3_USB_HUB")
			(options
				(clearance outline)
				(anchor circle)
			)
			(primitives
				(gr_poly
					(pts
						(arc
							(start 0.3048 0.2032)
							(mid 0.275042 0.275042)
							(end 0.2032 0.3048)
						)
						(arc
							(start -0.2032 0.3048)
							(mid -0.275042 0.275042)
							(end -0.3048 0.2032)
						)
						(arc
							(start -0.3048 -0.2032)
							(mid -0.275042 -0.275042)
							(end -0.2032 -0.3048)
						)
						(arc
							(start 0.2032 -0.3048)
							(mid 0.275042 -0.275042)
							(end 0.3048 -0.2032)
						)
					)
					(width 0)
					(fill yes)
				)
			)
		)
		(pad "2" smd custom
			(at 0 0.4445 90)
			(size 0.1524 0.1524)
			(layers "B.Cu" "B.Mask" "B.Paste")
			(net "GND")
			(options
				(clearance outline)
				(anchor circle)
			)
			(primitives
				(gr_poly
					(pts
						(arc
							(start 0.3048 0.2032)
							(mid 0.275042 0.275042)
							(end 0.2032 0.3048)
						)
						(arc
							(start -0.2032 0.3048)
							(mid -0.275042 0.275042)
							(end -0.3048 0.2032)
						)
						(arc
							(start -0.3048 -0.2032)
							(mid -0.275042 -0.275042)
							(end -0.2032 -0.3048)
						)
						(arc
							(start 0.2032 -0.3048)
							(mid 0.275042 -0.275042)
							(end 0.3048 -0.2032)
						)
					)
					(width 0)
					(fill yes)
				)
			)
		)
	)
)
